# T6G (Grand Teton) — schematic netlist excerpt (pin names and nets, part order shuffled) for the footprints in the layout excerpt that follows; sources: Cadence DE-HDL packaged netlist, KiCad conversion of 04192023_DAF0TMB3IC0_F0TG_MB_C_brd_V02_OCP.brd

C584  Q_CAP  10UF 6.3V 20% X6S  pkg C0402  page 279 : A = P0V9_CPU0_RT0_2A ; B = GND
R740  Q_RES  10K 5% EMPTY  pkg 0402LF  page 76 : A = PVDD18_S5_P0 ; B = CLK_CPU0_RTCCLK

(kicad_pcb
	(version 20260206)
	(generator "pcbnew")
	(generator_version "10.0")
	(general
		(thickness 1.6)
		(legacy_teardrops no)
	)
	(paper "A4")
	(title_block
		(title "04192023_DAF0TMB3IC0_F0TG_MB_C_brd_V02_OCP.brd")
		(comment 1 "Grand Teton / footprints 5045-5046 of 8354")
	)
	(layers
		(0 "F.Cu" signal "TOP")
		(4 "In1.Cu" signal "GND")
		(6 "In2.Cu" signal "IN1")
		(8 "In3.Cu" signal "GND1")
		(10 "In4.Cu" signal "IN2")
		(12 "In5.Cu" signal "GND2")
		(14 "In6.Cu" signal "IN3")
		(16 "In7.Cu" signal "GND3")
		(18 "In8.Cu" signal "VCC")
		(20 "In9.Cu" signal "VCC1")
		(22 "In10.Cu" signal "GND4")
		(24 "In11.Cu" signal "IN4")
		(26 "In12.Cu" signal "GND5")
		(28 "In13.Cu" signal "IN5")
		(30 "In14.Cu" signal "GND6")
		(32 "In15.Cu" signal "IN6")
		(34 "In16.Cu" signal "GND7")
		(2 "B.Cu" signal "BOTTOM")
		(9 "F.Adhes" user "F.Adhesive")
		(11 "B.Adhes" user "B.Adhesive")
		(13 "F.Paste" user "Package Geometry/Pastemask Top")
		(15 "B.Paste" user "Package Geometry/Pastemask Bottom")
		(5 "F.SilkS" user "Ref Des/Silkscreen Top")
		(7 "B.SilkS" user "Ref Des/Silkscreen Bottom")
		(1 "F.Mask" user "Board Geometry/Soldermask Top")
		(3 "B.Mask" user "Board Geometry/Soldermask Bottom")
		(17 "Dwgs.User" user "User.Drawings")
		(19 "Cmts.User" user "User.Comments")
		(21 "Eco1.User" user "User.Eco1")
		(23 "Eco2.User" user "User.Eco2")
		(25 "Edge.Cuts" user "Board Geometry/Outline")
		(27 "Margin" user)
		(31 "F.CrtYd" user "Package Geometry/Place Bound Top")
		(29 "B.CrtYd" user "Package Geometry/Place Bound Bottom")
		(35 "F.Fab" user "Ref Des/Assembly Top")
		(33 "B.Fab" user "Ref Des/Assembly Bottom")
	)
	(footprint ""
		(layer "B.Cu")
		(at 317.791084 -398.942052 90)
		(property "Reference" "C584"
			(at 0 0 90)
			(layer "B.SilkS")
			(hide yes)
			(effects
				(font
					(size 1.27 1.27)
				)
				(justify mirror)
			)
		)
		(property "Value" ""
			(at 0 0 90)
			(layer "B.Fab")
			(effects
				(font
					(size 1.27 1.27)
				)
				(justify mirror)
			)
		)
		(duplicate_pad_numbers_are_jumpers no)
		(fp_line
			(start 0.7874 -0.4064)
			(end -0.7874 -0.4064)
			(stroke
				(width 0.1524)
				(type default)
			)
			(layer "B.SilkS")
		)
		(fp_line
			(start -0.7874 -0.4064)
			(end -0.7874 0.4064)
			(stroke
				(width 0.1524)
				(type default)
			)
			(layer "B.SilkS")
		)
		(fp_line
			(start 0.7874 0.4064)
			(end 0.7874 -0.4064)
			(stroke
				(width 0.1524)
				(type default)
			)
			(layer "B.SilkS")
		)
		(fp_line
			(start -0.7874 0.4064)
			(end 0.7874 0.4064)
			(stroke
				(width 0.1524)
				(type default)
			)
			(layer "B.SilkS")
		)
		(fp_line
			(start 0.67945 -0.305054)
			(end 0.12065 -0.305054)
			(stroke
				(width 0.1)
				(type default)
			)
			(layer "B.Fab")
		)
		(fp_line
			(start 0.12065 -0.305054)
			(end 0.12065 -0.2794)
			(stroke
				(width 0.1)
				(type default)
			)
			(layer "B.Fab")
		)
		(fp_line
			(start -0.12065 -0.3048)
			(end -0.67945 -0.3048)
			(stroke
				(width 0.1)
				(type default)
			)
			(layer "B.Fab")
		)
		(fp_line
			(start -0.67945 -0.3048)
			(end -0.67945 0.3048)
			(stroke
				(width 0.1)
				(type default)
			)
			(layer "B.Fab")
		)
		(fp_line
			(start 0.12065 -0.2794)
			(end -0.12065 -0.2794)
			(stroke
				(width 0.1)
				(type default)
			)
			(layer "B.Fab")
		)
		(fp_line
			(start -0.12065 -0.2794)
			(end -0.12065 -0.3048)
			(stroke
				(width 0.1)
				(type default)
			)
			(layer "B.Fab")
		)
		(fp_line
			(start 0.12065 0.2794)
			(end 0.12065 0.3048)
			(stroke
				(width 0.1)
				(type default)
			)
			(layer "B.Fab")
		)
		(fp_line
			(start -0.120396 0.2794)
			(end 0.12065 0.2794)
			(stroke
				(width 0.1)
				(type default)
			)
			(layer "B.Fab")
		)
		(fp_line
			(start 0.67945 0.3048)
			(end 0.67945 -0.305054)
			(stroke
				(width 0.1)
				(type default)
			)
			(layer "B.Fab")
		)
		(fp_line
			(start 0.12065 0.3048)
			(end 0.67945 0.3048)
			(stroke
				(width 0.1)
				(type default)
			)
			(layer "B.Fab")
		)
		(fp_line
			(start -0.120396 0.3048)
			(end -0.120396 0.2794)
			(stroke
				(width 0.1)
				(type default)
			)
			(layer "B.Fab")
		)
		(fp_line
			(start -0.67945 0.3048)
			(end -0.120396 0.3048)
			(stroke
				(width 0.1)
				(type default)
			)
			(layer "B.Fab")
		)
		(pad "1" smd circle
			(at 0.40005 0 270)
			(size 0 0)
			(layers "B.Cu" "B.Mask" "B.Paste")
			(net "P0V9_CPU0_RT0_2A")
		)
		(pad "2" smd circle
			(at -0.40005 0 270)
			(size 0 0)
			(layers "B.Cu" "B.Mask" "B.Paste")
			(net "GND")
		)
	)
	(footprint ""
		(layer "B.Cu")
		(at 392.118088 -314.172854 90)
		(property "Reference" "R740"
			(at 0 0 90)
			(layer "B.SilkS")
			(hide yes)
			(effects
				(font
					(size 1.27 1.27)
				)
				(justify mirror)
			)
		)
		(property "Value" ""
			(at 0 0 90)
			(layer "B.Fab")
			(effects
				(font
					(size 1.27 1.27)
				)
				(justify mirror)
			)
		)
		(duplicate_pad_numbers_are_jumpers no)
		(fp_line
			(start 0.7874 -0.4064)
			(end -0.7874 -0.4064)
			(stroke
				(width 0.1524)
				(type default)
			)
			(layer "B.SilkS")
		)
		(fp_line
			(start -0.7874 -0.4064)
			(end -0.7874 0.4064)
			(stroke
				(width 0.1524)
				(type default)
			)
			(layer "B.SilkS")
		)
		(fp_line
			(start 0.7874 0.4064)
			(end 0.7874 -0.4064)
			(stroke
				(width 0.1524)
				(type default)
			)
			(layer "B.SilkS")
		)
		(fp_line
			(start -0.7874 0.4064)
			(end 0.7874 0.4064)
			(stroke
				(width 0.1524)
				(type default)
			)
			(layer "B.SilkS")
		)
		(fp_line
			(start 0.67945 -0.305054)
			(end 0.12065 -0.305054)
			(stroke
				(width 0.1)
				(type default)
			)
			(layer "B.Fab")
		)
		(fp_line
			(start 0.12065 -0.305054)
			(end 0.12065 -0.2794)
			(stroke
				(width 0.1)
				(type default)
			)
			(layer "B.Fab")
		)
		(fp_line
			(start -0.12065 -0.3048)
			(end -0.67945 -0.3048)
			(stroke
				(width 0.1)
				(type default)
			)
			(layer "B.Fab")
		)
		(fp_line
			(start -0.67945 -0.3048)
			(end -0.67945 0.3048)
			(stroke
				(width 0.1)
				(type default)
			)
			(layer "B.Fab")
		)
		(fp_line
			(start 0.12065 -0.2794)
			(end -0.12065 -0.2794)
			(stroke
				(width 0.1)
				(type default)
			)
			(layer "B.Fab")
		)
		(fp_line
			(start -0.12065 -0.2794)
			(end -0.12065 -0.3048)
			(stroke
				(width 0.1)
				(type default)
			)
			(layer "B.Fab")
		)
		(fp_line
			(start 0.12065 0.2794)
			(end 0.12065 0.3048)
			(stroke
				(width 0.1)
				(type default)
			)
			(layer "B.Fab")
		)
		(fp_line
			(start -0.120396 0.2794)
			(end 0.12065 0.2794)
			(stroke
				(width 0.1)
				(type default)
			)
			(layer "B.Fab")
		)
		(fp_line
			(start 0.67945 0.3048)
			(end 0.67945 -0.305054)
			(stroke
				(width 0.1)
				(type default)
			)
			(layer "B.Fab")
		)
		(fp_line
			(start 0.12065 0.3048)
			(end 0.67945 0.3048)
			(stroke
				(width 0.1)
				(type default)
			)
			(layer "B.Fab")
		)
		(fp_line
			(start -0.120396 0.3048)
			(end -0.120396 0.2794)
			(stroke
				(width 0.1)
				(type default)
			)
			(layer "B.Fab")
		)
		(fp_line
			(start -0.67945 0.3048)
			(end -0.120396 0.3048)
			(stroke
				(width 0.1)
				(type default)
			)
			(layer "B.Fab")
		)
		(pad "1" smd circle
			(at 0.40005 0 270)
			(size 0 0)
			(layers "B.Cu" "B.Mask" "B.Paste")
			(net "PVDD18_S5_P0")
		)
		(pad "2" smd circle
			(at -0.40005 0 270)
			(size 0 0)
			(layers "B.Cu" "B.Mask" "B.Paste")
			(net "CLK_CPU0_RTCCLK")
		)
	)
)
